(kicad_pcb
	(version 20241229)
	(generator "pcbnew")
	(generator_version "9.0")
	(general
		(thickness 1.61)
		(legacy_teardrops no)
	)
	(paper "A3")
	(title_block
		(title "RDIMM DDR5 Tester")
		(date "2026-05-21")
		(rev "2.2.0")
		(company "Antmicro")
		(comment 9 "footprints 386-391 of 796")
	)
	(layers
		(0 "F.Cu" signal)
		(4 "In1.Cu" power)
		(6 "In2.Cu" mixed)
		(8 "In3.Cu" power)
		(10 "In4.Cu" mixed)
		(12 "In5.Cu" power)
		(14 "In6.Cu" mixed)
		(16 "In7.Cu" power)
		(18 "In8.Cu" power)
		(20 "In9.Cu" mixed)
		(22 "In10.Cu" power)
		(2 "B.Cu" signal)
		(9 "F.Adhes" user "F.Adhesive")
		(11 "B.Adhes" user "B.Adhesive")
		(13 "F.Paste" user)
		(15 "B.Paste" user)
		(5 "F.SilkS" user "F.Silkscreen")
		(7 "B.SilkS" user "B.Silkscreen")
		(1 "F.Mask" user)
		(3 "B.Mask" user)
		(17 "Dwgs.User" user "User.Drawings")
		(19 "Cmts.User" user "User.Comments")
		(21 "Eco1.User" user "User.Eco1")
		(23 "Eco2.User" user "User.Eco2")
		(25 "Edge.Cuts" user)
		(27 "Margin" user)
		(31 "F.CrtYd" user "F.Courtyard")
		(29 "B.CrtYd" user "B.Courtyard")
		(35 "F.Fab" user)
		(33 "B.Fab" user)
	)
	(footprint "antmicro-footprints:R_0402_1005Metric"
		(layer "B.Cu")
		(at 139.575 150.025 90)
		(descr "Resistor SMD 0402")
		(tags "resistor SMD 0402")
		(property "Reference" "R102"
			(at -10.375 0.409 90)
			(layer "B.SilkS")
			(effects
				(font
					(size 0.7 0.7)
					(thickness 0.15)
				)
				(justify right bottom mirror)
			)
		)
		(property "Value" "R_10k_0402"
			(at -1.011843 -1.772047 90)
			(layer "B.Fab")
			(effects
				(font
					(size 0.7 0.7)
					(thickness 0.15)
				)
				(justify right bottom mirror)
			)
		)
		(property "Datasheet" "https://www.bourns.com/docs/product-datasheets/cr.pdf"
			(at 0 0 90)
			(layer "F.Fab")
			(hide yes)
			(effects
				(font
					(size 1.27 1.27)
					(thickness 0.15)
				)
			)
		)
		(property "Manufacturer" "Bourns"
			(at 0 0 90)
			(unlocked yes)
			(layer "B.Fab")
			(hide yes)
			(effects
				(font
					(size 1 1)
					(thickness 0.15)
				)
				(justify mirror)
			)
		)
		(property "MPN" "CR0402-FX-1002GLF"
			(at 0 0 90)
			(unlocked yes)
			(layer "B.Fab")
			(hide yes)
			(effects
				(font
					(size 1 1)
					(thickness 0.15)
				)
				(justify mirror)
			)
		)
		(property "Val" "10k"
			(at 0 0 90)
			(unlocked yes)
			(layer "B.Fab")
			(hide yes)
			(effects
				(font
					(size 1 1)
					(thickness 0.15)
				)
				(justify mirror)
			)
		)
		(property "License" "Apache-2.0"
			(at 0 0 90)
			(unlocked yes)
			(layer "B.Fab")
			(hide yes)
			(effects
				(font
					(size 1 1)
					(thickness 0.15)
				)
				(justify mirror)
			)
		)
		(property "Author" "Antmicro"
			(at 0 0 90)
			(unlocked yes)
			(layer "B.Fab")
			(hide yes)
			(effects
				(font
					(size 1 1)
					(thickness 0.15)
				)
				(justify mirror)
			)
		)
		(property "Tolerance" "1%"
			(at 0 0 90)
			(unlocked yes)
			(layer "B.Fab")
			(hide yes)
			(effects
				(font
					(size 1 1)
					(thickness 0.15)
				)
				(justify mirror)
			)
		)
		(sheetname "/Ethernet/")
		(sheetfile "ethernet.kicad_sch")
		(attr smd exclude_from_bom dnp)
		(fp_rect
			(start -0.925 0.47)
			(end 0.925 -0.47)
			(stroke
				(width 0.05)
				(type default)
			)
			(fill no)
			(layer "B.CrtYd")
		)
		(fp_rect
			(start -0.5 0.25)
			(end 0.5 -0.25)
			(stroke
				(width 0.15)
				(type solid)
			)
			(fill no)
			(layer "B.Fab")
		)
		(fp_text user "${REFERENCE}"
			(at -0.95 -3.168 270)
			(layer "B.Fab")
			(effects
				(font
					(size 0.7 0.7)
					(thickness 0.15)
				)
				(justify left bottom mirror)
			)
		)
		(fp_text user "Author: Antmicro"
			(at -0.95 -4.169 270)
			(layer "B.Fab")
			(effects
				(font
					(size 0.7 0.7)
					(thickness 0.15)
				)
				(justify left bottom mirror)
			)
		)
		(fp_text user "License: Apache-2.0"
			(at -0.95 -5.169 270)
			(layer "B.Fab")
			(effects
				(font
					(size 0.7 0.7)
					(thickness 0.15)
				)
				(justify left bottom mirror)
			)
		)
		(pad "1" smd roundrect
			(at -0.48 0 90)
			(size 0.59 0.64)
			(layers "B.Cu" "B.Mask" "B.Paste")
			(roundrect_rratio 0.25)
			(net 394 "/Ethernet/ETH.RXD1")
			(pintype "passive")
		)
		(pad "2" smd roundrect
			(at 0.48 0 90)
			(size 0.59 0.64)
			(layers "B.Cu" "B.Mask" "B.Paste")
			(roundrect_rratio 0.25)
			(net 797 "+1V8")
			(pintype "passive")
		)
	)
	(footprint "antmicro-footprints:R_0402_1005Metric"
		(layer "B.Cu")
		(at 142.75 150.05 90)
		(descr "Resistor SMD 0402")
		(tags "resistor SMD 0402")
		(property "Reference" "R105"
			(at -10.375 0.409 90)
			(layer "B.SilkS")
			(effects
				(font
					(size 0.7 0.7)
					(thickness 0.15)
				)
				(justify right bottom mirror)
			)
		)
		(property "Value" "R_10k_0402"
			(at -1.011843 -1.772047 90)
			(layer "B.Fab")
			(effects
				(font
					(size 0.7 0.7)
					(thickness 0.15)
				)
				(justify right bottom mirror)
			)
		)
		(property "Datasheet" "https://www.bourns.com/docs/product-datasheets/cr.pdf"
			(at 0 0 90)
			(layer "F.Fab")
			(hide yes)
			(effects
				(font
					(size 1.27 1.27)
					(thickness 0.15)
				)
			)
		)
		(property "Manufacturer" "Bourns"
			(at 0 0 90)
			(unlocked yes)
			(layer "B.Fab")
			(hide yes)
			(effects
				(font
					(size 1 1)
					(thickness 0.15)
				)
				(justify mirror)
			)
		)
		(property "MPN" "CR0402-FX-1002GLF"
			(at 0 0 90)
			(unlocked yes)
			(layer "B.Fab")
			(hide yes)
			(effects
				(font
					(size 1 1)
					(thickness 0.15)
				)
				(justify mirror)
			)
		)
		(property "Val" "10k"
			(at 0 0 90)
			(unlocked yes)
			(layer "B.Fab")
			(hide yes)
			(effects
				(font
					(size 1 1)
					(thickness 0.15)
				)
				(justify mirror)
			)
		)
		(property "License" "Apache-2.0"
			(at 0 0 90)
			(unlocked yes)
			(layer "B.Fab")
			(hide yes)
			(effects
				(font
					(size 1 1)
					(thickness 0.15)
				)
				(justify mirror)
			)
		)
		(property "Author" "Antmicro"
			(at 0 0 90)
			(unlocked yes)
			(layer "B.Fab")
			(hide yes)
			(effects
				(font
					(size 1 1)
					(thickness 0.15)
				)
				(justify mirror)
			)
		)
		(property "Tolerance" "1%"
			(at 0 0 90)
			(unlocked yes)
			(layer "B.Fab")
			(hide yes)
			(effects
				(font
					(size 1 1)
					(thickness 0.15)
				)
				(justify mirror)
			)
		)
		(sheetname "/Ethernet/")
		(sheetfile "ethernet.kicad_sch")
		(attr smd exclude_from_bom dnp)
		(fp_rect
			(start -0.925 0.47)
			(end 0.925 -0.47)
			(stroke
				(width 0.05)
				(type default)
			)
			(fill no)
			(layer "B.CrtYd")
		)
		(fp_rect
			(start -0.5 0.25)
			(end 0.5 -0.25)
			(stroke
				(width 0.15)
				(type solid)
			)
			(fill no)
			(layer "B.Fab")
		)
		(fp_text user "${REFERENCE}"
			(at -0.95 -3.168 270)
			(layer "B.Fab")
			(effects
				(font
					(size 0.7 0.7)
					(thickness 0.15)
				)
				(justify left bottom mirror)
			)
		)
		(fp_text user "License: Apache-2.0"
			(at -0.95 -5.169 270)
			(layer "B.Fab")
			(effects
				(font
					(size 0.7 0.7)
					(thickness 0.15)
				)
				(justify left bottom mirror)
			)
		)
		(fp_text user "Author: Antmicro"
			(at -0.95 -4.169 270)
			(layer "B.Fab")
			(effects
				(font
					(size 0.7 0.7)
					(thickness 0.15)
				)
				(justify left bottom mirror)
			)
		)
		(pad "1" smd roundrect
			(at -0.48 0 90)
			(size 0.59 0.64)
			(layers "B.Cu" "B.Mask" "B.Paste")
			(roundrect_rratio 0.25)
			(net 397 "/Ethernet/ETH.RX_CTL")
			(pintype "passive")
		)
		(pad "2" smd roundrect
			(at 0.48 0 90)
			(size 0.59 0.64)
			(layers "B.Cu" "B.Mask" "B.Paste")
			(roundrect_rratio 0.25)
			(net 797 "+1V8")
			(pintype "passive")
		)
	)
	(footprint "antmicro-footprints:R_0402_1005Metric"
		(layer "B.Cu")
		(at 141.65 150.025 90)
		(descr "Resistor SMD 0402")
		(tags "resistor SMD 0402")
		(property "Reference" "R106"
			(at -10.375 0.409 90)
			(layer "B.SilkS")
			(effects
				(font
					(size 0.7 0.7)
					(thickness 0.15)
				)
				(justify right bottom mirror)
			)
		)
		(property "Value" "R_10k_0402"
			(at -1.011843 -1.772047 90)
			(layer "B.Fab")
			(effects
				(font
					(size 0.7 0.7)
					(thickness 0.15)
				)
				(justify right bottom mirror)
			)
		)
		(property "Datasheet" "https://www.bourns.com/docs/product-datasheets/cr.pdf"
			(at 0 0 90)
			(layer "F.Fab")
			(hide yes)
			(effects
				(font
					(size 1.27 1.27)
					(thickness 0.15)
				)
			)
		)
		(property "Manufacturer" "Bourns"
			(at 0 0 90)
			(unlocked yes)
			(layer "B.Fab")
			(hide yes)
			(effects
				(font
					(size 1 1)
					(thickness 0.15)
				)
				(justify mirror)
			)
		)
		(property "MPN" "CR0402-FX-1002GLF"
			(at 0 0 90)
			(unlocked yes)
			(layer "B.Fab")
			(hide yes)
			(effects
				(font
					(size 1 1)
					(thickness 0.15)
				)
				(justify mirror)
			)
		)
		(property "Val" "10k"
			(at 0 0 90)
			(unlocked yes)
			(layer "B.Fab")
			(hide yes)
			(effects
				(font
					(size 1 1)
					(thickness 0.15)
				)
				(justify mirror)
			)
		)
		(property "License" "Apache-2.0"
			(at 0 0 90)
			(unlocked yes)
			(layer "B.Fab")
			(hide yes)
			(effects
				(font
					(size 1 1)
					(thickness 0.15)
				)
				(justify mirror)
			)
		)
		(property "Author" "Antmicro"
			(at 0 0 90)
			(unlocked yes)
			(layer "B.Fab")
			(hide yes)
			(effects
				(font
					(size 1 1)
					(thickness 0.15)
				)
				(justify mirror)
			)
		)
		(property "Tolerance" "1%"
			(at 0 0 90)
			(unlocked yes)
			(layer "B.Fab")
			(hide yes)
			(effects
				(font
					(size 1 1)
					(thickness 0.15)
				)
				(justify mirror)
			)
		)
		(sheetname "/Ethernet/")
		(sheetfile "ethernet.kicad_sch")
		(attr smd exclude_from_bom dnp)
		(fp_rect
			(start -0.925 0.47)
			(end 0.925 -0.47)
			(stroke
				(width 0.05)
				(type default)
			)
			(fill no)
			(layer "B.CrtYd")
		)
		(fp_rect
			(start -0.5 0.25)
			(end 0.5 -0.25)
			(stroke
				(width 0.15)
				(type solid)
			)
			(fill no)
			(layer "B.Fab")
		)
		(fp_text user "License: Apache-2.0"
			(at -0.95 -5.169 270)
			(layer "B.Fab")
			(effects
				(font
					(size 0.7 0.7)
					(thickness 0.15)
				)
				(justify left bottom mirror)
			)
		)
		(fp_text user "${REFERENCE}"
			(at -0.95 -3.168 270)
			(layer "B.Fab")
			(effects
				(font
					(size 0.7 0.7)
					(thickness 0.15)
				)
				(justify left bottom mirror)
			)
		)
		(fp_text user "Author: Antmicro"
			(at -0.95 -4.169 270)
			(layer "B.Fab")
			(effects
				(font
					(size 0.7 0.7)
					(thickness 0.15)
				)
				(justify left bottom mirror)
			)
		)
		(pad "1" smd roundrect
			(at -0.48 0 90)
			(size 0.59 0.64)
			(layers "B.Cu" "B.Mask" "B.Paste")
			(roundrect_rratio 0.25)
			(net 398 "/Ethernet/ETH.RXC")
			(pintype "passive")
		)
		(pad "2" smd roundrect
			(at 0.48 0 90)
			(size 0.59 0.64)
			(layers "B.Cu" "B.Mask" "B.Paste")
			(roundrect_rratio 0.25)
			(net 797 "+1V8")
			(pintype "passive")
		)
	)
	(footprint "antmicro-footprints:R_0402_1005Metric"
		(layer "B.Cu")
		(at 136.433171 143.399 90)
		(descr "Resistor SMD 0402")
		(tags "resistor SMD 0402")
		(property "Reference" "R107"
			(at -1.701 -3.603171 90)
			(layer "B.SilkS")
			(hide yes)
			(effects
				(font
					(size 0.7 0.7)
					(thickness 0.15)
				)
				(justify right bottom mirror)
			)
		)
		(property "Value" "R_10k_0402"
			(at -1.011843 -1.772047 90)
			(layer "B.Fab")
			(effects
				(font
					(size 0.7 0.7)
					(thickness 0.15)
				)
				(justify right bottom mirror)
			)
		)
		(property "Datasheet" "https://www.bourns.com/docs/product-datasheets/cr.pdf"
			(at 0 0 90)
			(layer "F.Fab")
			(hide yes)
			(effects
				(font
					(size 1.27 1.27)
					(thickness 0.15)
				)
			)
		)
		(property "Manufacturer" "Bourns"
			(at 0 0 90)
			(unlocked yes)
			(layer "B.Fab")
			(hide yes)
			(effects
				(font
					(size 1 1)
					(thickness 0.15)
				)
				(justify mirror)
			)
		)
		(property "MPN" "CR0402-FX-1002GLF"
			(at 0 0 90)
			(unlocked yes)
			(layer "B.Fab")
			(hide yes)
			(effects
				(font
					(size 1 1)
					(thickness 0.15)
				)
				(justify mirror)
			)
		)
		(property "Val" "10k"
			(at 0 0 90)
			(unlocked yes)
			(layer "B.Fab")
			(hide yes)
			(effects
				(font
					(size 1 1)
					(thickness 0.15)
				)
				(justify mirror)
			)
		)
		(property "License" "Apache-2.0"
			(at 0 0 90)
			(unlocked yes)
			(layer "B.Fab")
			(hide yes)
			(effects
				(font
					(size 1 1)
					(thickness 0.15)
				)
				(justify mirror)
			)
		)
		(property "Author" "Antmicro"
			(at 0 0 90)
			(unlocked yes)
			(layer "B.Fab")
			(hide yes)
			(effects
				(font
					(size 1 1)
					(thickness 0.15)
				)
				(justify mirror)
			)
		)
		(property "Tolerance" "1%"
			(at 0 0 90)
			(unlocked yes)
			(layer "B.Fab")
			(hide yes)
			(effects
				(font
					(size 1 1)
					(thickness 0.15)
				)
				(justify mirror)
			)
		)
		(sheetname "/Ethernet/")
		(sheetfile "ethernet.kicad_sch")
		(attr smd)
		(fp_rect
			(start -0.925 0.47)
			(end 0.925 -0.47)
			(stroke
				(width 0.05)
				(type default)
			)
			(fill no)
			(layer "B.CrtYd")
		)
		(fp_rect
			(start -0.5 0.25)
			(end 0.5 -0.25)
			(stroke
				(width 0.15)
				(type solid)
			)
			(fill no)
			(layer "B.Fab")
		)
		(fp_text user "License: Apache-2.0"
			(at -0.95 -5.169 270)
			(layer "B.Fab")
			(effects
				(font
					(size 0.7 0.7)
					(thickness 0.15)
				)
				(justify left bottom mirror)
			)
		)
		(fp_text user "${REFERENCE}"
			(at -0.95 -3.168 270)
			(layer "B.Fab")
			(effects
				(font
					(size 0.7 0.7)
					(thickness 0.15)
				)
				(justify left bottom mirror)
			)
		)
		(fp_text user "Author: Antmicro"
			(at -0.95 -4.169 270)
			(layer "B.Fab")
			(effects
				(font
					(size 0.7 0.7)
					(thickness 0.15)
				)
				(justify left bottom mirror)
			)
		)
		(pad "1" smd roundrect
			(at -0.48 0 90)
			(size 0.59 0.64)
			(layers "B.Cu" "B.Mask" "B.Paste")
			(roundrect_rratio 0.25)
			(net 399 "/Ethernet/ETH.REF_CLK")
			(pintype "passive")
		)
		(pad "2" smd roundrect
			(at 0.48 0 90)
			(size 0.59 0.64)
			(layers "B.Cu" "B.Mask" "B.Paste")
			(roundrect_rratio 0.25)
			(net 797 "+1V8")
			(pintype "passive")
		)
	)
	(footprint "antmicro-footprints:R_0402_1005Metric"
		(layer "B.Cu")
		(at 139.224499 142.249)
		(descr "Resistor SMD 0402")
		(tags "resistor SMD 0402")
		(property "Reference" "R111"
			(at 0.983501 0.499 0)
			(layer "B.SilkS")
			(effects
				(font
					(size 0.7 0.7)
					(thickness 0.15)
				)
				(justify right bottom mirror)
			)
		)
		(property "Value" "R_10k_0402"
			(at -1.011843 -1.772047 0)
			(layer "B.Fab")
			(effects
				(font
					(size 0.7 0.7)
					(thickness 0.15)
				)
				(justify right bottom mirror)
			)
		)
		(property "Datasheet" "https://www.bourns.com/docs/product-datasheets/cr.pdf"
			(at 0 0 0)
			(layer "F.Fab")
			(hide yes)
			(effects
				(font
					(size 1.27 1.27)
					(thickness 0.15)
				)
			)
		)
		(property "Manufacturer" "Bourns"
			(at 0 0 0)
			(unlocked yes)
			(layer "B.Fab")
			(hide yes)
			(effects
				(font
					(size 1 1)
					(thickness 0.15)
				)
				(justify mirror)
			)
		)
		(property "MPN" "CR0402-FX-1002GLF"
			(at 0 0 0)
			(unlocked yes)
			(layer "B.Fab")
			(hide yes)
			(effects
				(font
					(size 1 1)
					(thickness 0.15)
				)
				(justify mirror)
			)
		)
		(property "Val" "10k"
			(at 0 0 0)
			(unlocked yes)
			(layer "B.Fab")
			(hide yes)
			(effects
				(font
					(size 1 1)
					(thickness 0.15)
				)
				(justify mirror)
			)
		)
		(property "License" "Apache-2.0"
			(at 0 0 0)
			(unlocked yes)
			(layer "B.Fab")
			(hide yes)
			(effects
				(font
					(size 1 1)
					(thickness 0.15)
				)
				(justify mirror)
			)
		)
		(property "Author" "Antmicro"
			(at 0 0 0)
			(unlocked yes)
			(layer "B.Fab")
			(hide yes)
			(effects
				(font
					(size 1 1)
					(thickness 0.15)
				)
				(justify mirror)
			)
		)
		(property "Tolerance" "1%"
			(at 0 0 0)
			(unlocked yes)
			(layer "B.Fab")
			(hide yes)
			(effects
				(font
					(size 1 1)
					(thickness 0.15)
				)
				(justify mirror)
			)
		)
		(sheetname "/Ethernet/")
		(sheetfile "ethernet.kicad_sch")
		(attr smd)
		(fp_rect
			(start -0.925 0.47)
			(end 0.925 -0.47)
			(stroke
				(width 0.05)
				(type default)
			)
			(fill no)
			(layer "B.CrtYd")
		)
		(fp_rect
			(start -0.5 0.25)
			(end 0.5 -0.25)
			(stroke
				(width 0.15)
				(type solid)
			)
			(fill no)
			(layer "B.Fab")
		)
		(fp_text user "License: Apache-2.0"
			(at -0.95 -5.169 180)
			(layer "B.Fab")
			(effects
				(font
					(size 0.7 0.7)
					(thickness 0.15)
				)
				(justify left bottom mirror)
			)
		)
		(fp_text user "Author: Antmicro"
			(at -0.95 -4.169 180)
			(layer "B.Fab")
			(effects
				(font
					(size 0.7 0.7)
					(thickness 0.15)
				)
				(justify left bottom mirror)
			)
		)
		(fp_text user "${REFERENCE}"
			(at -0.95 -3.168 180)
			(layer "B.Fab")
			(effects
				(font
					(size 0.7 0.7)
					(thickness 0.15)
				)
				(justify left bottom mirror)
			)
		)
		(pad "1" smd roundrect
			(at -0.48 0)
			(size 0.59 0.64)
			(layers "B.Cu" "B.Mask" "B.Paste")
			(roundrect_rratio 0.25)
			(net 401 "/Ethernet/ETH.~{RESET}")
			(pintype "passive")
		)
		(pad "2" smd roundrect
			(at 0.48 0)
			(size 0.59 0.64)
			(layers "B.Cu" "B.Mask" "B.Paste")
			(roundrect_rratio 0.25)
			(net 797 "+1V8")
			(pintype "passive")
		)
	)
	(footprint "antmicro-footprints:R_0402_1005Metric"
		(layer "B.Cu")
		(at 126.325 141.262149 180)
		(descr "Resistor SMD 0402")
		(tags "resistor SMD 0402")
		(property "Reference" "R108"
			(at 2.200501 -0.486851 0)
			(layer "B.SilkS")
			(effects
				(font
					(size 0.7 0.7)
					(thickness 0.15)
				)
				(justify left bottom mirror)
			)
		)
		(property "Value" "R_10k_0402"
			(at -1.011843 -1.772047 0)
			(layer "B.Fab")
			(effects
				(font
					(size 0.7 0.7)
					(thickness 0.15)
				)
				(justify left bottom mirror)
			)
		)
		(property "Datasheet" "https://www.bourns.com/docs/product-datasheets/cr.pdf"
			(at 0 0 180)
			(layer "F.Fab")
			(hide yes)
			(effects
				(font
					(size 1.27 1.27)
					(thickness 0.15)
				)
			)
		)
		(property "Manufacturer" "Bourns"
			(at 0 0 180)
			(unlocked yes)
			(layer "B.Fab")
			(hide yes)
			(effects
				(font
					(size 1 1)
					(thickness 0.15)
				)
				(justify mirror)
			)
		)
		(property "MPN" "CR0402-FX-1002GLF"
			(at 0 0 180)
			(unlocked yes)
			(layer "B.Fab")
			(hide yes)
			(effects
				(font
					(size 1 1)
					(thickness 0.15)
				)
				(justify mirror)
			)
		)
		(property "Val" "10k"
			(at 0 0 180)
			(unlocked yes)
			(layer "B.Fab")
			(hide yes)
			(effects
				(font
					(size 1 1)
					(thickness 0.15)
				)
				(justify mirror)
			)
		)
		(property "License" "Apache-2.0"
			(at 0 0 180)
			(unlocked yes)
			(layer "B.Fab")
			(hide yes)
			(effects
				(font
					(size 1 1)
					(thickness 0.15)
				)
				(justify mirror)
			)
		)
		(property "Author" "Antmicro"
			(at 0 0 180)
			(unlocked yes)
			(layer "B.Fab")
			(hide yes)
			(effects
				(font
					(size 1 1)
					(thickness 0.15)
				)
				(justify mirror)
			)
		)
		(property "Tolerance" "1%"
			(at 0 0 180)
			(unlocked yes)
			(layer "B.Fab")
			(hide yes)
			(effects
				(font
					(size 1 1)
					(thickness 0.15)
				)
				(justify mirror)
			)
		)
		(sheetname "/Ethernet/")
		(sheetfile "ethernet.kicad_sch")
		(attr smd)
		(fp_rect
			(start -0.925 0.47)
			(end 0.925 -0.47)
			(stroke
				(width 0.05)
				(type default)
			)
			(fill no)
			(layer "B.CrtYd")
		)
		(fp_rect
			(start -0.5 0.25)
			(end 0.5 -0.25)
			(stroke
				(width 0.15)
				(type solid)
			)
			(fill no)
			(layer "B.Fab")
		)
		(fp_text user "License: Apache-2.0"
			(at -0.95 -5.169 0)
			(layer "B.Fab")
			(effects
				(font
					(size 0.7 0.7)
					(thickness 0.15)
				)
				(justify left bottom mirror)
			)
		)
		(fp_text user "Author: Antmicro"
			(at -0.95 -4.169 0)
			(layer "B.Fab")
			(effects
				(font
					(size 0.7 0.7)
					(thickness 0.15)
				)
				(justify left bottom mirror)
			)
		)
		(fp_text user "${REFERENCE}"
			(at -0.95 -3.168 0)
			(layer "B.Fab")
			(effects
				(font
					(size 0.7 0.7)
					(thickness 0.15)
				)
				(justify left bottom mirror)
			)
		)
		(pad "1" smd roundrect
			(at -0.48 0 180)
			(size 0.59 0.64)
			(layers "B.Cu" "B.Mask" "B.Paste")
			(roundrect_rratio 0.25)
			(net 330 "/Ethernet/LED_SPD")
			(pintype "passive")
		)
		(pad "2" smd roundrect
			(at 0.48 0 180)
			(size 0.59 0.64)
			(layers "B.Cu" "B.Mask" "B.Paste")
			(roundrect_rratio 0.25)
			(net 797 "+1V8")
			(pintype "passive")
		)
	)
)
